(kicad_pcb
	(version 20241229)
	(generator "pcbnew")
	(generator_version "9.0")
	(general
		(thickness 1.711)
		(legacy_teardrops no)
	)
	(paper "A4")
	(title_block
		(title "Antmicro Baseboard for Jetson AGX Thor")
		(date "2026-02-18")
		(rev "1.1.0")
		(company "Antmicro Ltd")
		(comment 1 "www.antmicro.com")
		(comment 9 "footprints 212-216 of 1170")
	)
	(layers
		(0 "F.Cu" signal)
		(4 "In1.Cu" signal)
		(6 "In2.Cu" signal)
		(8 "In3.Cu" signal)
		(10 "In4.Cu" jumper)
		(12 "In5.Cu" signal)
		(14 "In6.Cu" signal)
		(16 "In7.Cu" signal)
		(18 "In8.Cu" signal)
		(2 "B.Cu" signal)
		(9 "F.Adhes" user "F.Adhesive")
		(11 "B.Adhes" user "B.Adhesive")
		(13 "F.Paste" user)
		(15 "B.Paste" user)
		(5 "F.SilkS" user "F.Silkscreen")
		(7 "B.SilkS" user "B.Silkscreen")
		(1 "F.Mask" user)
		(3 "B.Mask" user)
		(17 "Dwgs.User" user "User.Drawings")
		(19 "Cmts.User" user "User.Comments")
		(21 "Eco1.User" user "User.Eco1")
		(23 "Eco2.User" user "User.Eco2")
		(25 "Edge.Cuts" user)
		(27 "Margin" user)
		(31 "F.CrtYd" user "F.Courtyard")
		(29 "B.CrtYd" user "B.Courtyard")
		(35 "F.Fab" user)
		(33 "B.Fab" user)
	)
	(footprint "antmicro-footprints:R_0402_1005Metric"
		(layer "F.Cu")
		(at 212.1 133.1 180)
		(descr "Resistor SMD 0402")
		(tags "resistor SMD 0402")
		(property "Reference" "R85"
			(at 2.9 0.4 0)
			(layer "F.SilkS")
			(effects
				(font
					(size 0.7 0.7)
					(thickness 0.15)
				)
				(justify right top)
			)
		)
		(property "Value" "R_12k_0402"
			(at -1.011843 1.772047 0)
			(layer "F.Fab")
			(effects
				(font
					(size 0.7 0.7)
					(thickness 0.15)
				)
				(justify right top)
			)
		)
		(property "Datasheet" "https://www.bourns.com/docs/product-datasheets/cr.pdf"
			(at 0 0 0)
			(layer "F.Fab")
			(hide yes)
			(effects
				(font
					(size 1.27 1.27)
					(thickness 0.15)
				)
			)
		)
		(property "Description" "SMD Chip Resistor, 12 kohm, ± 1%, 62.5 mW, 0402 [1005 Metric], Thick Film, General Purpose"
			(at 0 0 0)
			(layer "F.Fab")
			(hide yes)
			(effects
				(font
					(size 1.27 1.27)
					(thickness 0.15)
				)
			)
		)
		(property "MPN" "CR0402-FX-1202GLF"
			(at 0 0 180)
			(unlocked yes)
			(layer "F.Fab")
			(hide yes)
			(effects
				(font
					(size 1 1)
					(thickness 0.15)
				)
			)
		)
		(property "Manufacturer" "Bourns"
			(at 0 0 180)
			(unlocked yes)
			(layer "F.Fab")
			(hide yes)
			(effects
				(font
					(size 1 1)
					(thickness 0.15)
				)
			)
		)
		(property "License" "Apache-2.0"
			(at 0 0 180)
			(unlocked yes)
			(layer "F.Fab")
			(hide yes)
			(effects
				(font
					(size 1 1)
					(thickness 0.15)
				)
			)
		)
		(property "Author" "Antmicro"
			(at 0 0 180)
			(unlocked yes)
			(layer "F.Fab")
			(hide yes)
			(effects
				(font
					(size 1 1)
					(thickness 0.15)
				)
			)
		)
		(property "Val" "12k"
			(at 0 0 180)
			(unlocked yes)
			(layer "F.Fab")
			(hide yes)
			(effects
				(font
					(size 1 1)
					(thickness 0.15)
				)
			)
		)
		(property "Tolerance" "1%"
			(at 0 0 180)
			(unlocked yes)
			(layer "F.Fab")
			(hide yes)
			(effects
				(font
					(size 1 1)
					(thickness 0.15)
				)
			)
		)
		(sheetname "/USB Hub/")
		(sheetfile "usb_hub.kicad_sch")
		(attr smd)
		(fp_rect
			(start -0.925 -0.47)
			(end 0.925 0.47)
			(stroke
				(width 0.05)
				(type default)
			)
			(fill no)
			(layer "F.CrtYd")
		)
		(fp_rect
			(start -0.5 -0.25)
			(end 0.5 0.25)
			(stroke
				(width 0.15)
				(type solid)
			)
			(fill no)
			(layer "F.Fab")
		)
		(fp_text user "${REFERENCE}"
			(at -0.95 3.168 0)
			(layer "F.Fab")
			(effects
				(font
					(size 0.7 0.7)
					(thickness 0.15)
				)
				(justify right top)
			)
		)
		(fp_text user "Author: Antmicro"
			(at -0.95 4.169 0)
			(layer "F.Fab")
			(effects
				(font
					(size 0.7 0.7)
					(thickness 0.15)
				)
				(justify right top)
			)
		)
		(fp_text user "License: Apache-2.0"
			(at -0.95 5.169 0)
			(layer "F.Fab")
			(effects
				(font
					(size 0.7 0.7)
					(thickness 0.15)
				)
				(justify right top)
			)
		)
		(pad "1" smd roundrect
			(at -0.48 0 180)
			(size 0.59 0.64)
			(layers "F.Cu" "F.Mask" "F.Paste")
			(roundrect_rratio 0.25)
			(net 1 "GND")
			(pintype "passive")
		)
		(pad "2" smd roundrect
			(at 0.48 0 180)
			(size 0.59 0.64)
			(layers "F.Cu" "F.Mask" "F.Paste")
			(roundrect_rratio 0.25)
			(net 919 "Net-(U21-RBIAS)")
			(pintype "passive")
		)
	)
	(footprint "antmicro-footprints:C_0402_1005Metric"
		(layer "F.Cu")
		(at 162.249468 79.51)
		(descr "Capacitor SMD 0402")
		(tags "capacitor SMD 0402")
		(property "Reference" "C386"
			(at -5.549468 0.49 0)
			(layer "F.SilkS")
			(effects
				(font
					(size 0.7 0.7)
					(thickness 0.15)
				)
				(justify left bottom)
			)
		)
		(property "Value" "C_100n_0402"
			(at -1.022927 2.155213 0)
			(layer "F.Fab")
			(effects
				(font
					(size 0.7 0.7)
					(thickness 0.15)
				)
				(justify left bottom)
			)
		)
		(property "Datasheet" "https://www.murata.com/products/productdetail?partno=GRM155R61H104KE14%23"
			(at 0 0 0)
			(layer "F.Fab")
			(hide yes)
			(effects
				(font
					(size 1.27 1.27)
					(thickness 0.15)
				)
			)
		)
		(property "Description" "SMD Multilayer Ceramic Capacitor, 0.1 µF, 50 V, 0402 [1005 Metric], ± 10%, X5R, GRM Series"
			(at 0 0 0)
			(layer "F.Fab")
			(hide yes)
			(effects
				(font
					(size 1.27 1.27)
					(thickness 0.15)
				)
			)
		)
		(property "Manufacturer" "Murata"
			(at 0 0 0)
			(unlocked yes)
			(layer "F.Fab")
			(hide yes)
			(effects
				(font
					(size 1 1)
					(thickness 0.15)
				)
			)
		)
		(property "MPN" "GRM155R61H104KE14D"
			(at 0 0 0)
			(unlocked yes)
			(layer "F.Fab")
			(hide yes)
			(effects
				(font
					(size 1 1)
					(thickness 0.15)
				)
			)
		)
		(property "Val" "100n"
			(at 0 0 0)
			(unlocked yes)
			(layer "F.Fab")
			(hide yes)
			(effects
				(font
					(size 1 1)
					(thickness 0.15)
				)
			)
		)
		(property "License" "Apache-2.0"
			(at 0 0 0)
			(unlocked yes)
			(layer "F.Fab")
			(hide yes)
			(effects
				(font
					(size 1 1)
					(thickness 0.15)
				)
			)
		)
		(property "Author" "Antmicro"
			(at 0 0 0)
			(unlocked yes)
			(layer "F.Fab")
			(hide yes)
			(effects
				(font
					(size 1 1)
					(thickness 0.15)
				)
			)
		)
		(property "Voltage" "50V"
			(at 0 0 0)
			(unlocked yes)
			(layer "F.Fab")
			(hide yes)
			(effects
				(font
					(size 1 1)
					(thickness 0.15)
				)
			)
		)
		(property "Dielectric" "X5R"
			(at 0 0 0)
			(unlocked yes)
			(layer "F.Fab")
			(hide yes)
			(effects
				(font
					(size 1 1)
					(thickness 0.15)
				)
			)
		)
		(component_classes
			(class "DCDC_20V")
		)
		(sheetname "/DCDC/")
		(sheetfile "dcdc.kicad_sch")
		(attr smd)
		(fp_rect
			(start -0.925 -0.47)
			(end 0.925 0.47)
			(stroke
				(width 0.05)
				(type default)
			)
			(fill no)
			(layer "F.CrtYd")
		)
		(fp_line
			(start -0.494 -0.25)
			(end 0.504 -0.25)
			(stroke
				(width 0.15)
				(type solid)
			)
			(layer "F.Fab")
		)
		(fp_line
			(start -0.494 0.248)
			(end -0.494 -0.25)
			(stroke
				(width 0.15)
				(type solid)
			)
			(layer "F.Fab")
		)
		(fp_line
			(start 0.504 -0.25)
			(end 0.504 0.248)
			(stroke
				(width 0.15)
				(type solid)
			)
			(layer "F.Fab")
		)
		(fp_line
			(start 0.504 0.248)
			(end -0.494 0.248)
			(stroke
				(width 0.15)
				(type solid)
			)
			(layer "F.Fab")
		)
		(fp_text user "License: Apache-2.0"
			(at -0.939 5.799 0)
			(layer "F.Fab")
			(effects
				(font
					(size 0.7 0.7)
					(thickness 0.15)
				)
				(justify left bottom)
			)
		)
		(fp_text user "Author: Antmicro"
			(at -0.939 3.399 0)
			(layer "F.Fab")
			(effects
				(font
					(size 0.7 0.7)
					(thickness 0.15)
				)
				(justify left bottom)
			)
		)
		(fp_text user "${REFERENCE}"
			(at -0.939 4.599 0)
			(layer "F.Fab")
			(effects
				(font
					(size 0.7 0.7)
					(thickness 0.15)
				)
				(justify left bottom)
			)
		)
		(pad "1" smd roundrect
			(at -0.48 0)
			(size 0.59 0.64)
			(layers "F.Cu" "F.Mask" "F.Paste")
			(roundrect_rratio 0.25)
			(net 1221 "Net-(U66-IN-)")
			(pintype "passive")
		)
		(pad "2" smd roundrect
			(at 0.48 0)
			(size 0.59 0.64)
			(layers "F.Cu" "F.Mask" "F.Paste")
			(roundrect_rratio 0.25)
			(net 1284 "Net-(U66-IN+)")
			(pintype "passive")
		)
	)
	(footprint "antmicro-footprints:R_0402_1005Metric"
		(layer "F.Cu")
		(at 201.7 135.7 180)
		(descr "Resistor SMD 0402")
		(tags "resistor SMD 0402")
		(property "Reference" "R66"
			(at 2.9 0.4 0)
			(layer "F.SilkS")
			(effects
				(font
					(size 0.7 0.7)
					(thickness 0.15)
				)
				(justify right top)
			)
		)
		(property "Value" "R_11k_0402"
			(at -1.011843 1.772046 0)
			(layer "F.Fab")
			(effects
				(font
					(size 0.7 0.7)
					(thickness 0.15)
				)
				(justify right top)
			)
		)
		(property "Datasheet" "https://www.bourns.com/docs/product-datasheets/cr.pdf"
			(at 0 0 0)
			(layer "F.Fab")
			(hide yes)
			(effects
				(font
					(size 1.27 1.27)
					(thickness 0.15)
				)
			)
		)
		(property "Description" "SMD Chip Resistor, 11 kohm, ± 1%, 62.5 mW, 0402 [1005 Metric], Thick Film, General Purpose"
			(at 0 0 0)
			(layer "F.Fab")
			(hide yes)
			(effects
				(font
					(size 1.27 1.27)
					(thickness 0.15)
				)
			)
		)
		(property "MPN" "CR0402-FX-1102GLF"
			(at 0 0 180)
			(unlocked yes)
			(layer "F.Fab")
			(hide yes)
			(effects
				(font
					(size 1 1)
					(thickness 0.15)
				)
			)
		)
		(property "Manufacturer" "Bourns"
			(at 0 0 180)
			(unlocked yes)
			(layer "F.Fab")
			(hide yes)
			(effects
				(font
					(size 1 1)
					(thickness 0.15)
				)
			)
		)
		(property "License" "Apache-2.0"
			(at 0 0 180)
			(unlocked yes)
			(layer "F.Fab")
			(hide yes)
			(effects
				(font
					(size 1 1)
					(thickness 0.15)
				)
			)
		)
		(property "Author" "Antmicro"
			(at 0 0 180)
			(unlocked yes)
			(layer "F.Fab")
			(hide yes)
			(effects
				(font
					(size 1 1)
					(thickness 0.15)
				)
			)
		)
		(property "Val" "11k"
			(at 0 0 180)
			(unlocked yes)
			(layer "F.Fab")
			(hide yes)
			(effects
				(font
					(size 1 1)
					(thickness 0.15)
				)
			)
		)
		(property "Tolerance" "1%"
			(at 0 0 180)
			(unlocked yes)
			(layer "F.Fab")
			(hide yes)
			(effects
				(font
					(size 1 1)
					(thickness 0.15)
				)
			)
		)
		(sheetname "/USB Hub/")
		(sheetfile "usb_hub.kicad_sch")
		(attr smd)
		(fp_poly
			(pts
				(xy -0.925 -0.47) (xy -0.925 0.47) (xy 0.925 0.47) (xy 0.925 -0.47)
			)
			(stroke
				(width 0.05)
				(type default)
			)
			(fill no)
			(layer "F.CrtYd")
		)
		(fp_poly
			(pts
				(xy -0.5 -0.25) (xy -0.5 0.25) (xy 0.5 0.25) (xy 0.5 -0.25)
			)
			(stroke
				(width 0.15)
				(type solid)
			)
			(fill no)
			(layer "F.Fab")
		)
		(fp_text user "${REFERENCE}"
			(at -0.95 3.168 0)
			(layer "F.Fab")
			(effects
				(font
					(size 0.7 0.7)
					(thickness 0.15)
				)
				(justify right top)
			)
		)
		(fp_text user "Author: Antmicro"
			(at -0.95 4.169 0)
			(layer "F.Fab")
			(effects
				(font
					(size 0.7 0.7)
					(thickness 0.15)
				)
				(justify right top)
			)
		)
		(fp_text user "License: Apache-2.0"
			(at -0.949999 5.169 0)
			(layer "F.Fab")
			(effects
				(font
					(size 0.7 0.7)
					(thickness 0.15)
				)
				(justify right top)
			)
		)
		(pad "1" smd roundrect
			(at -0.48 0 180)
			(size 0.59 0.64)
			(layers "F.Cu" "F.Mask" "F.Paste")
			(roundrect_rratio 0.25)
			(net 1164 "/USB Hub/VBUS_MON_UP")
			(pintype "passive")
		)
		(pad "2" smd roundrect
			(at 0.48 0 180)
			(size 0.59 0.64)
			(layers "F.Cu" "F.Mask" "F.Paste")
			(roundrect_rratio 0.25)
			(net 2 "+3V3")
			(pintype "passive")
		)
	)
	(footprint "antmicro-footprints:R_0402_1005Metric"
		(layer "F.Cu")
		(at 132.85 56.27 90)
		(descr "Resistor SMD 0402")
		(tags "resistor SMD 0402")
		(property "Reference" "R251"
			(at -2.46 11.53 90)
			(layer "F.SilkS")
			(effects
				(font
					(size 0.7 0.7)
					(thickness 0.15)
				)
				(justify left bottom)
			)
		)
		(property "Value" "R_2k37_0402"
			(at -1.011843 1.772047 90)
			(layer "F.Fab")
			(effects
				(font
					(size 0.7 0.7)
					(thickness 0.15)
				)
				(justify left bottom)
			)
		)
		(property "Datasheet" "https://www.bourns.com/docs/product-datasheets/cr.pdf"
			(at 0 0 90)
			(layer "F.Fab")
			(hide yes)
			(effects
				(font
					(size 1.27 1.27)
					(thickness 0.15)
				)
			)
		)
		(property "Description" "SMD Chip Resistor"
			(at 0 0 90)
			(layer "F.Fab")
			(hide yes)
			(effects
				(font
					(size 1.27 1.27)
					(thickness 0.15)
				)
			)
		)
		(property "Manufacturer" "Bourns"
			(at 0 0 90)
			(unlocked yes)
			(layer "F.Fab")
			(hide yes)
			(effects
				(font
					(size 1 1)
					(thickness 0.15)
				)
			)
		)
		(property "MPN" "CR0402-FX-2371GLF"
			(at 0 0 90)
			(unlocked yes)
			(layer "F.Fab")
			(hide yes)
			(effects
				(font
					(size 1 1)
					(thickness 0.15)
				)
			)
		)
		(property "Val" "2k37"
			(at 0 0 90)
			(unlocked yes)
			(layer "F.Fab")
			(hide yes)
			(effects
				(font
					(size 1 1)
					(thickness 0.15)
				)
			)
		)
		(property "License" "Apache-2.0"
			(at 0 0 90)
			(unlocked yes)
			(layer "F.Fab")
			(hide yes)
			(effects
				(font
					(size 1 1)
					(thickness 0.15)
				)
			)
		)
		(property "Author" "Antmicro"
			(at 0 0 90)
			(unlocked yes)
			(layer "F.Fab")
			(hide yes)
			(effects
				(font
					(size 1 1)
					(thickness 0.15)
				)
			)
		)
		(property "Tolerance" "1%"
			(at 0 0 90)
			(unlocked yes)
			(layer "F.Fab")
			(hide yes)
			(effects
				(font
					(size 1 1)
					(thickness 0.15)
				)
			)
		)
		(sheetname "/DCDC/")
		(sheetfile "dcdc.kicad_sch")
		(attr smd)
		(fp_rect
			(start -0.925 -0.47)
			(end 0.925 0.47)
			(stroke
				(width 0.05)
				(type default)
			)
			(fill no)
			(layer "F.CrtYd")
		)
		(fp_rect
			(start -0.5 -0.25)
			(end 0.5 0.25)
			(stroke
				(width 0.15)
				(type solid)
			)
			(fill no)
			(layer "F.Fab")
		)
		(fp_text user "License: Apache-2.0"
			(at -0.95 5.169 90)
			(layer "F.Fab")
			(effects
				(font
					(size 0.7 0.7)
					(thickness 0.15)
				)
				(justify left bottom)
			)
		)
		(fp_text user "Author: Antmicro"
			(at -0.95 4.169 90)
			(layer "F.Fab")
			(effects
				(font
					(size 0.7 0.7)
					(thickness 0.15)
				)
				(justify left bottom)
			)
		)
		(fp_text user "${REFERENCE}"
			(at -0.95 3.168 90)
			(layer "F.Fab")
			(effects
				(font
					(size 0.7 0.7)
					(thickness 0.15)
				)
				(justify left bottom)
			)
		)
		(pad "1" smd roundrect
			(at -0.48 0 90)
			(size 0.59 0.64)
			(layers "F.Cu" "F.Mask" "F.Paste")
			(roundrect_rratio 0.25)
			(net 1 "GND")
			(pintype "passive")
		)
		(pad "2" smd roundrect
			(at 0.48 0 90)
			(size 0.59 0.64)
			(layers "F.Cu" "F.Mask" "F.Paste")
			(roundrect_rratio 0.25)
			(net 1305 "/DCDC/5V_{AON}_EN")
			(pintype "passive")
		)
	)
	(footprint "antmicro-footprints:C_0402_1005Metric"
		(layer "F.Cu")
		(at 206.75 91.470856 180)
		(descr "Capacitor SMD 0402")
		(tags "capacitor SMD 0402")
		(property "Reference" "C320"
			(at 3.65 -0.929144 180)
			(layer "F.SilkS")
			(effects
				(font
					(size 0.7 0.7)
					(thickness 0.15)
				)
				(justify left bottom)
			)
		)
		(property "Value" "C_100n_0402"
			(at -1.022927 2.155213 180)
			(layer "F.Fab")
			(effects
				(font
					(size 0.7 0.7)
					(thickness 0.15)
				)
				(justify left bottom)
			)
		)
		(property "Datasheet" "https://www.murata.com/products/productdetail?partno=GRM155R61H104KE14%23"
			(at 0 0 180)
			(layer "F.Fab")
			(hide yes)
			(effects
				(font
					(size 1.27 1.27)
					(thickness 0.15)
				)
			)
		)
		(property "Description" "SMD Multilayer Ceramic Capacitor, 0.1 µF, 50 V, 0402 [1005 Metric], ± 10%, X5R, GRM Series"
			(at 0 0 180)
			(layer "F.Fab")
			(hide yes)
			(effects
				(font
					(size 1.27 1.27)
					(thickness 0.15)
				)
			)
		)
		(property "Manufacturer" "Murata"
			(at 0 0 180)
			(unlocked yes)
			(layer "F.Fab")
			(hide yes)
			(effects
				(font
					(size 1 1)
					(thickness 0.15)
				)
			)
		)
		(property "MPN" "GRM155R61H104KE14D"
			(at 0 0 180)
			(unlocked yes)
			(layer "F.Fab")
			(hide yes)
			(effects
				(font
					(size 1 1)
					(thickness 0.15)
				)
			)
		)
		(property "Val" "100n"
			(at 0 0 180)
			(unlocked yes)
			(layer "F.Fab")
			(hide yes)
			(effects
				(font
					(size 1 1)
					(thickness 0.15)
				)
			)
		)
		(property "License" "Apache-2.0"
			(at 0 0 180)
			(unlocked yes)
			(layer "F.Fab")
			(hide yes)
			(effects
				(font
					(size 1 1)
					(thickness 0.15)
				)
			)
		)
		(property "Author" "Antmicro"
			(at 0 0 180)
			(unlocked yes)
			(layer "F.Fab")
			(hide yes)
			(effects
				(font
					(size 1 1)
					(thickness 0.15)
				)
			)
		)
		(property "Voltage" "50V"
			(at 0 0 180)
			(unlocked yes)
			(layer "F.Fab")
			(hide yes)
			(effects
				(font
					(size 1 1)
					(thickness 0.15)
				)
			)
		)
		(property "Dielectric" "X5R"
			(at 0 0 180)
			(unlocked yes)
			(layer "F.Fab")
			(hide yes)
			(effects
				(font
					(size 1 1)
					(thickness 0.15)
				)
			)
		)
		(sheetname "/SoM_IO2/")
		(sheetfile "som_io2.kicad_sch")
		(attr smd)
		(fp_rect
			(start -0.925 -0.47)
			(end 0.925 0.47)
			(stroke
				(width 0.05)
				(type default)
			)
			(fill no)
			(layer "F.CrtYd")
		)
		(fp_line
			(start 0.504 0.248)
			(end -0.494 0.248)
			(stroke
				(width 0.15)
				(type solid)
			)
			(layer "F.Fab")
		)
		(fp_line
			(start 0.504 -0.25)
			(end 0.504 0.248)
			(stroke
				(width 0.15)
				(type solid)
			)
			(layer "F.Fab")
		)
		(fp_line
			(start -0.494 0.248)
			(end -0.494 -0.25)
			(stroke
				(width 0.15)
				(type solid)
			)
			(layer "F.Fab")
		)
		(fp_line
			(start -0.494 -0.25)
			(end 0.504 -0.25)
			(stroke
				(width 0.15)
				(type solid)
			)
			(layer "F.Fab")
		)
		(fp_text user "Author: Antmicro"
			(at -0.939 3.399 180)
			(layer "F.Fab")
			(effects
				(font
					(size 0.7 0.7)
					(thickness 0.15)
				)
				(justify left bottom)
			)
		)
		(fp_text user "${REFERENCE}"
			(at -0.939 4.599 180)
			(layer "F.Fab")
			(effects
				(font
					(size 0.7 0.7)
					(thickness 0.15)
				)
				(justify left bottom)
			)
		)
		(fp_text user "License: Apache-2.0"
			(at -0.939 5.799 180)
			(layer "F.Fab")
			(effects
				(font
					(size 0.7 0.7)
					(thickness 0.15)
				)
				(justify left bottom)
			)
		)
		(pad "1" smd roundrect
			(at -0.48 0 180)
			(size 0.59 0.64)
			(layers "F.Cu" "F.Mask" "F.Paste")
			(roundrect_rratio 0.25)
			(net 557 "/SoM_IO2/DP0.TX3+")
			(pintype "passive")
		)
		(pad "2" smd roundrect
			(at 0.48 0 180)
			(size 0.59 0.64)
			(layers "F.Cu" "F.Mask" "F.Paste")
			(roundrect_rratio 0.25)
			(net 746 "/SoM_IO2/DP0.TX3_C+")
			(pintype "passive")
		)
	)
)
